(kicad_pcb
	(version 20241229)
	(generator "pcbnew")
	(generator_version "9.0")
	(general
		(thickness 1.62)
		(legacy_teardrops no)
	)
	(paper "A3")
	(title_block
		(title "COM Express 7 Baseboard")
		(date "2025-02-04")
		(rev "1.1.2")
		(company "Antmicro Ltd")
		(comment 1 "www.antmicro.com")
		(comment 9 "footprints 708-712 of 802")
	)
	(layers
		(0 "F.Cu" signal)
		(4 "In1.Cu" signal)
		(6 "In2.Cu" signal)
		(8 "In3.Cu" signal)
		(10 "In4.Cu" signal)
		(12 "In5.Cu" signal)
		(14 "In6.Cu" signal)
		(2 "B.Cu" signal)
		(9 "F.Adhes" user "F.Adhesive")
		(11 "B.Adhes" user "B.Adhesive")
		(13 "F.Paste" user)
		(15 "B.Paste" user)
		(5 "F.SilkS" user "F.Silkscreen")
		(7 "B.SilkS" user "B.Silkscreen")
		(1 "F.Mask" user)
		(3 "B.Mask" user)
		(17 "Dwgs.User" user "User.Drawings")
		(19 "Cmts.User" user "User.Comments")
		(21 "Eco1.User" user "User.Eco1")
		(23 "Eco2.User" user "User.Eco2")
		(25 "Edge.Cuts" user)
		(27 "Margin" user)
		(31 "F.CrtYd" user "F.Courtyard")
		(29 "B.CrtYd" user "B.Courtyard")
		(35 "F.Fab" user)
		(33 "B.Fab" user)
	)
	(footprint "antmicro-footprints:C_0402_1005Metric"
		(layer "B.Cu")
		(at 133.29 141.36 -90)
		(descr "Capacitor SMD 0402")
		(tags "capacitor SMD 0402")
		(property "Reference" "C195"
			(at 0.8 -0.11 90)
			(layer "B.SilkS")
			(effects
				(font
					(size 0.7 0.7)
					(thickness 0.15)
				)
				(justify left bottom mirror)
			)
		)
		(property "Value" "C_100n_0402"
			(at -1.022927 -2.155213 90)
			(layer "B.Fab")
			(effects
				(font
					(size 0.7 0.7)
					(thickness 0.15)
				)
				(justify left bottom mirror)
			)
		)
		(property "Datasheet" "https://www.murata.com/products/productdetail?partno=GRM155R61H104KE14%23"
			(at 0 0 270)
			(layer "F.Fab")
			(hide yes)
			(effects
				(font
					(size 1.27 1.27)
					(thickness 0.15)
				)
			)
		)
		(property "Author" "Antmicro"
			(at -8.07 274.65 0)
			(layer "B.Fab")
			(hide yes)
			(effects
				(font
					(size 1 1)
					(thickness 0.15)
				)
				(justify mirror)
			)
		)
		(property "Dielectric" "X5R"
			(at -8.07 274.65 0)
			(layer "B.Fab")
			(hide yes)
			(effects
				(font
					(size 1 1)
					(thickness 0.15)
				)
				(justify mirror)
			)
		)
		(property "License" "Apache-2.0"
			(at -8.07 274.65 0)
			(layer "B.Fab")
			(hide yes)
			(effects
				(font
					(size 1 1)
					(thickness 0.15)
				)
				(justify mirror)
			)
		)
		(property "MPN" "GRM155R61H104KE14D"
			(at -8.07 274.65 0)
			(layer "B.Fab")
			(hide yes)
			(effects
				(font
					(size 1 1)
					(thickness 0.15)
				)
				(justify mirror)
			)
		)
		(property "Manufacturer" "Murata"
			(at -8.07 274.65 0)
			(layer "B.Fab")
			(hide yes)
			(effects
				(font
					(size 1 1)
					(thickness 0.15)
				)
				(justify mirror)
			)
		)
		(property "Public" "False"
			(at -8.07 274.65 0)
			(layer "B.Fab")
			(hide yes)
			(effects
				(font
					(size 1 1)
					(thickness 0.15)
				)
				(justify mirror)
			)
		)
		(property "Val" "100n"
			(at -8.07 274.65 0)
			(layer "B.Fab")
			(hide yes)
			(effects
				(font
					(size 1 1)
					(thickness 0.15)
				)
				(justify mirror)
			)
		)
		(property "Voltage" "50V"
			(at -8.07 274.65 0)
			(layer "B.Fab")
			(hide yes)
			(effects
				(font
					(size 1 1)
					(thickness 0.15)
				)
				(justify mirror)
			)
		)
		(sheetname "KR to SFI #2")
		(sheetfile "kr_sfi.kicad_sch")
		(attr smd)
		(fp_rect
			(start -0.925 0.47)
			(end 0.925 -0.47)
			(stroke
				(width 0.05)
				(type default)
			)
			(fill no)
			(layer "B.CrtYd")
		)
		(fp_line
			(start -0.494 0.25)
			(end -0.494 -0.248)
			(stroke
				(width 0.15)
				(type solid)
			)
			(layer "B.Fab")
		)
		(fp_line
			(start 0.504 0.25)
			(end -0.494 0.25)
			(stroke
				(width 0.15)
				(type solid)
			)
			(layer "B.Fab")
		)
		(fp_line
			(start -0.494 -0.248)
			(end 0.504 -0.248)
			(stroke
				(width 0.15)
				(type solid)
			)
			(layer "B.Fab")
		)
		(fp_line
			(start 0.504 -0.248)
			(end 0.504 0.25)
			(stroke
				(width 0.15)
				(type solid)
			)
			(layer "B.Fab")
		)
		(pad "1" smd roundrect
			(at -0.48 0 270)
			(size 0.59 0.64)
			(layers "B.Cu" "B.Mask" "B.Paste")
			(roundrect_rratio 0.25)
			(net 1 "GND")
			(pintype "passive")
			(teardrops
				(best_length_ratio 0.2)
				(max_length 1)
				(best_width_ratio 0.9)
				(max_width 2)
				(curved_edges yes)
				(filter_ratio 0.9)
				(enabled yes)
				(allow_two_segments yes)
				(prefer_zone_connections yes)
			)
		)
		(pad "2" smd roundrect
			(at 0.48 0 270)
			(size 0.59 0.64)
			(layers "B.Cu" "B.Mask" "B.Paste")
			(roundrect_rratio 0.25)
			(net 74 "+1V0")
			(pintype "passive")
			(teardrops
				(best_length_ratio 0.2)
				(max_length 1)
				(best_width_ratio 0.9)
				(max_width 2)
				(curved_edges yes)
				(filter_ratio 0.9)
				(enabled yes)
				(allow_two_segments yes)
				(prefer_zone_connections yes)
			)
		)
	)
	(footprint "antmicro-footprints:C_0402_1005Metric"
		(layer "B.Cu")
		(at 151.45 139.36 -90)
		(descr "Capacitor SMD 0402")
		(tags "capacitor SMD 0402")
		(property "Reference" "C163"
			(at -1.05 -1.4 90)
			(layer "B.SilkS")
			(effects
				(font
					(size 0.7 0.7)
					(thickness 0.15)
				)
				(justify left bottom mirror)
			)
		)
		(property "Value" "C_100n_0402"
			(at -1.022927 -2.155213 90)
			(layer "B.Fab")
			(effects
				(font
					(size 0.7 0.7)
					(thickness 0.15)
				)
				(justify left bottom mirror)
			)
		)
		(property "Datasheet" "https://www.murata.com/products/productdetail?partno=GRM155R61H104KE14%23"
			(at 0 0 270)
			(layer "F.Fab")
			(hide yes)
			(effects
				(font
					(size 1.27 1.27)
					(thickness 0.15)
				)
			)
		)
		(property "Author" "Antmicro"
			(at 12.09 290.81 0)
			(layer "B.Fab")
			(hide yes)
			(effects
				(font
					(size 1 1)
					(thickness 0.15)
				)
				(justify mirror)
			)
		)
		(property "Dielectric" "X5R"
			(at 12.09 290.81 0)
			(layer "B.Fab")
			(hide yes)
			(effects
				(font
					(size 1 1)
					(thickness 0.15)
				)
				(justify mirror)
			)
		)
		(property "License" "Apache-2.0"
			(at 12.09 290.81 0)
			(layer "B.Fab")
			(hide yes)
			(effects
				(font
					(size 1 1)
					(thickness 0.15)
				)
				(justify mirror)
			)
		)
		(property "MPN" "GRM155R61H104KE14D"
			(at 12.09 290.81 0)
			(layer "B.Fab")
			(hide yes)
			(effects
				(font
					(size 1 1)
					(thickness 0.15)
				)
				(justify mirror)
			)
		)
		(property "Manufacturer" "Murata"
			(at 12.09 290.81 0)
			(layer "B.Fab")
			(hide yes)
			(effects
				(font
					(size 1 1)
					(thickness 0.15)
				)
				(justify mirror)
			)
		)
		(property "Public" "False"
			(at 12.09 290.81 0)
			(layer "B.Fab")
			(hide yes)
			(effects
				(font
					(size 1 1)
					(thickness 0.15)
				)
				(justify mirror)
			)
		)
		(property "Val" "100n"
			(at 12.09 290.81 0)
			(layer "B.Fab")
			(hide yes)
			(effects
				(font
					(size 1 1)
					(thickness 0.15)
				)
				(justify mirror)
			)
		)
		(property "Voltage" "50V"
			(at 12.09 290.81 0)
			(layer "B.Fab")
			(hide yes)
			(effects
				(font
					(size 1 1)
					(thickness 0.15)
				)
				(justify mirror)
			)
		)
		(sheetname "KR to SFI #1")
		(sheetfile "kr_sfi.kicad_sch")
		(attr smd)
		(fp_rect
			(start -0.925 0.47)
			(end 0.925 -0.47)
			(stroke
				(width 0.05)
				(type default)
			)
			(fill no)
			(layer "B.CrtYd")
		)
		(fp_line
			(start -0.494 0.25)
			(end -0.494 -0.248)
			(stroke
				(width 0.15)
				(type solid)
			)
			(layer "B.Fab")
		)
		(fp_line
			(start 0.504 0.25)
			(end -0.494 0.25)
			(stroke
				(width 0.15)
				(type solid)
			)
			(layer "B.Fab")
		)
		(fp_line
			(start -0.494 -0.248)
			(end 0.504 -0.248)
			(stroke
				(width 0.15)
				(type solid)
			)
			(layer "B.Fab")
		)
		(fp_line
			(start 0.504 -0.248)
			(end 0.504 0.25)
			(stroke
				(width 0.15)
				(type solid)
			)
			(layer "B.Fab")
		)
		(pad "1" smd roundrect
			(at -0.48 0 270)
			(size 0.59 0.64)
			(layers "B.Cu" "B.Mask" "B.Paste")
			(roundrect_rratio 0.25)
			(net 1 "GND")
			(pintype "passive")
			(teardrops
				(best_length_ratio 0.2)
				(max_length 1)
				(best_width_ratio 0.9)
				(max_width 2)
				(curved_edges yes)
				(filter_ratio 0.9)
				(enabled yes)
				(allow_two_segments yes)
				(prefer_zone_connections yes)
			)
		)
		(pad "2" smd roundrect
			(at 0.48 0 270)
			(size 0.59 0.64)
			(layers "B.Cu" "B.Mask" "B.Paste")
			(roundrect_rratio 0.25)
			(net 74 "+1V0")
			(pintype "passive")
			(teardrops
				(best_length_ratio 0.2)
				(max_length 1)
				(best_width_ratio 0.9)
				(max_width 2)
				(curved_edges yes)
				(filter_ratio 0.9)
				(enabled yes)
				(allow_two_segments yes)
				(prefer_zone_connections yes)
			)
		)
	)
	(footprint "antmicro-footprints:R_0805_2012Metric"
		(layer "B.Cu")
		(at 105.04 152.65 180)
		(property "Reference" "R82"
			(at -4 -0.5 0)
			(layer "B.SilkS")
			(effects
				(font
					(size 0.7 0.7)
					(thickness 0.15)
				)
				(justify left bottom mirror)
			)
		)
		(property "Value" "R_0R001_0805"
			(at 0 -1.8 0)
			(layer "B.Fab")
			(effects
				(font
					(size 0.7 0.7)
					(thickness 0.15)
				)
				(justify left bottom mirror)
			)
		)
		(property "Datasheet" "https://www.eaton.com/content/dam/eaton/products/electronic-components/resources/data-sheet/eaton-msma-automotive-smd-current-sense-resistor-metal-strip-data-sheet-elx1179.pdf"
			(at 0 0 180)
			(layer "F.Fab")
			(hide yes)
			(effects
				(font
					(size 1.27 1.27)
					(thickness 0.15)
				)
			)
		)
		(property "Author" "Antmicro"
			(at 210.08 305.67 0)
			(layer "B.Fab")
			(hide yes)
			(effects
				(font
					(size 1 1)
					(thickness 0.15)
				)
				(justify mirror)
			)
		)
		(property "License" "Apache-2.0"
			(at 210.08 305.67 0)
			(layer "B.Fab")
			(hide yes)
			(effects
				(font
					(size 1 1)
					(thickness 0.15)
				)
				(justify mirror)
			)
		)
		(property "MPN" "MSMA0805R0010FSM"
			(at 210.08 305.67 0)
			(layer "B.Fab")
			(hide yes)
			(effects
				(font
					(size 1 1)
					(thickness 0.15)
				)
				(justify mirror)
			)
		)
		(property "Manufacturer" "Eaton"
			(at 210.08 305.67 0)
			(layer "B.Fab")
			(hide yes)
			(effects
				(font
					(size 1 1)
					(thickness 0.15)
				)
				(justify mirror)
			)
		)
		(property "Public" "False"
			(at 210.08 305.67 0)
			(layer "B.Fab")
			(hide yes)
			(effects
				(font
					(size 1 1)
					(thickness 0.15)
				)
				(justify mirror)
			)
		)
		(property "Tolerance" "1%"
			(at 210.08 305.67 0)
			(layer "B.Fab")
			(hide yes)
			(effects
				(font
					(size 1 1)
					(thickness 0.15)
				)
				(justify mirror)
			)
		)
		(property "Val" "0R001"
			(at 210.08 305.67 0)
			(layer "B.Fab")
			(hide yes)
			(effects
				(font
					(size 1 1)
					(thickness 0.15)
				)
				(justify mirror)
			)
		)
		(sheetname "OCuLink")
		(sheetfile "oculink.kicad_sch")
		(attr smd)
		(fp_line
			(start 0.298 0.701)
			(end -0.3 0.701)
			(stroke
				(width 0.15)
				(type solid)
			)
			(layer "B.SilkS")
		)
		(fp_line
			(start 0.28 -0.699)
			(end -0.32 -0.699)
			(stroke
				(width 0.15)
				(type solid)
			)
			(layer "B.SilkS")
		)
		(fp_rect
			(start 1.95 0.9)
			(end -1.95 -0.9)
			(stroke
				(width 0.05)
				(type default)
			)
			(fill no)
			(layer "B.CrtYd")
		)
		(fp_line
			(start 0.949 0.682)
			(end -0.951 0.682)
			(stroke
				(width 0.15)
				(type solid)
			)
			(layer "B.Fab")
		)
		(fp_line
			(start 0.949 -0.675)
			(end 0.949 0.677)
			(stroke
				(width 0.15)
				(type solid)
			)
			(layer "B.Fab")
		)
		(fp_line
			(start 0.949 -0.68)
			(end -0.951 -0.68)
			(stroke
				(width 0.15)
				(type solid)
			)
			(layer "B.Fab")
		)
		(fp_line
			(start -0.951 -0.675)
			(end -0.951 0.677)
			(stroke
				(width 0.15)
				(type solid)
			)
			(layer "B.Fab")
		)
		(pad "1" smd roundrect
			(at -1.1 0 180)
			(size 1.2 1.3)
			(layers "B.Cu" "B.Mask" "B.Paste")
			(roundrect_rratio 0.25)
			(net 52 "+5V")
			(pintype "passive")
			(teardrops
				(best_length_ratio 0.2)
				(max_length 1)
				(best_width_ratio 0.9)
				(max_width 2)
				(curved_edges yes)
				(filter_ratio 0.9)
				(enabled yes)
				(allow_two_segments yes)
				(prefer_zone_connections yes)
			)
		)
		(pad "2" smd roundrect
			(at 1.1 0 180)
			(size 1.2 1.3)
			(layers "B.Cu" "B.Mask" "B.Paste")
			(roundrect_rratio 0.25)
			(net 61 "/OCuLink/5V_CONN0")
			(pintype "passive")
			(teardrops
				(best_length_ratio 0.2)
				(max_length 1)
				(best_width_ratio 0.9)
				(max_width 2)
				(curved_edges yes)
				(filter_ratio 0.9)
				(enabled yes)
				(allow_two_segments yes)
				(prefer_zone_connections yes)
			)
		)
	)
	(footprint "antmicro-footprints:R_0402_1005Metric"
		(layer "B.Cu")
		(at 148.05 169.16 -90)
		(descr "Resistor SMD 0402")
		(tags "resistor SMD 0402")
		(property "Reference" "R57"
			(at -3.9 13.5 270)
			(layer "B.SilkS")
			(effects
				(font
					(size 0.7 0.7)
					(thickness 0.15)
				)
				(justify left bottom mirror)
			)
		)
		(property "Value" "R_0R_0402"
			(at -1.011843 -1.772047 90)
			(layer "B.Fab")
			(effects
				(font
					(size 0.7 0.7)
					(thickness 0.15)
				)
				(justify left bottom mirror)
			)
		)
		(property "Datasheet" "https://industrial.panasonic.com/cdbs/www-data/pdf/RDA0000/AOA0000C301.pdf"
			(at 0 0 270)
			(layer "F.Fab")
			(hide yes)
			(effects
				(font
					(size 1.27 1.27)
					(thickness 0.15)
				)
			)
		)
		(property "Author" "Antmicro"
			(at -21.11 317.21 0)
			(layer "B.Fab")
			(hide yes)
			(effects
				(font
					(size 1 1)
					(thickness 0.15)
				)
				(justify mirror)
			)
		)
		(property "Current" "1A"
			(at -21.11 317.21 0)
			(layer "B.Fab")
			(hide yes)
			(effects
				(font
					(size 1 1)
					(thickness 0.15)
				)
				(justify mirror)
			)
		)
		(property "License" "Apache-2.0"
			(at -21.11 317.21 0)
			(layer "B.Fab")
			(hide yes)
			(effects
				(font
					(size 1 1)
					(thickness 0.15)
				)
				(justify mirror)
			)
		)
		(property "MPN" "ERJ2GE0R00X"
			(at -21.11 317.21 0)
			(layer "B.Fab")
			(hide yes)
			(effects
				(font
					(size 1 1)
					(thickness 0.15)
				)
				(justify mirror)
			)
		)
		(property "Manufacturer" "Panasonic"
			(at -21.11 317.21 0)
			(layer "B.Fab")
			(hide yes)
			(effects
				(font
					(size 1 1)
					(thickness 0.15)
				)
				(justify mirror)
			)
		)
		(property "Public" "False"
			(at -21.11 317.21 0)
			(layer "B.Fab")
			(hide yes)
			(effects
				(font
					(size 1 1)
					(thickness 0.15)
				)
				(justify mirror)
			)
		)
		(property "Tolerance" ""
			(at -21.11 317.21 0)
			(layer "B.Fab")
			(hide yes)
			(effects
				(font
					(size 1 1)
					(thickness 0.15)
				)
				(justify mirror)
			)
		)
		(property "Val" "0R"
			(at -21.11 317.21 0)
			(layer "B.Fab")
			(hide yes)
			(effects
				(font
					(size 1 1)
					(thickness 0.15)
				)
				(justify mirror)
			)
		)
		(sheetname "2xSFP+")
		(sheetfile "2xSFP+.kicad_sch")
		(attr smd)
		(fp_rect
			(start -0.925 0.47)
			(end 0.925 -0.47)
			(stroke
				(width 0.05)
				(type default)
			)
			(fill no)
			(layer "B.CrtYd")
		)
		(fp_rect
			(start -0.5 0.25)
			(end 0.5 -0.25)
			(stroke
				(width 0.15)
				(type solid)
			)
			(fill no)
			(layer "B.Fab")
		)
		(pad "1" smd roundrect
			(at -0.48 0 270)
			(size 0.59 0.64)
			(layers "B.Cu" "B.Mask" "B.Paste")
			(roundrect_rratio 0.25)
			(net 163 "Net-(J2A-TX_{DISABLE})")
			(pintype "passive")
			(teardrops
				(best_length_ratio 0.2)
				(max_length 1)
				(best_width_ratio 0.9)
				(max_width 2)
				(curved_edges yes)
				(filter_ratio 0.9)
				(enabled yes)
				(allow_two_segments yes)
				(prefer_zone_connections yes)
			)
		)
		(pad "2" smd roundrect
			(at 0.48 0 270)
			(size 0.59 0.64)
			(layers "B.Cu" "B.Mask" "B.Paste")
			(roundrect_rratio 0.25)
			(net 1 "GND")
			(pintype "passive")
			(teardrops
				(best_length_ratio 0.2)
				(max_length 1)
				(best_width_ratio 0.9)
				(max_width 2)
				(curved_edges yes)
				(filter_ratio 0.9)
				(enabled yes)
				(allow_two_segments yes)
				(prefer_zone_connections yes)
			)
		)
	)
	(footprint "antmicro-footprints:C_0603_1608Metric"
		(layer "B.Cu")
		(at 286.75 79.12 -90)
		(descr "Capacitor SMD 0603")
		(tags "capacitor 0603")
		(property "Reference" "C75"
			(at -3.36 -0.42 90)
			(layer "B.SilkS")
			(effects
				(font
					(size 0.7 0.7)
					(thickness 0.15)
				)
				(justify left bottom mirror)
			)
		)
		(property "Value" "C_22u_16V_0603"
			(at -1.42757 -1.770288 90)
			(layer "B.Fab")
			(effects
				(font
					(size 0.7 0.7)
					(thickness 0.15)
				)
				(justify left bottom mirror)
			)
		)
		(property "Datasheet" "https://product.samsungsem.com/mlcc/CL10A226MO7JZN.do"
			(at 0 0 270)
			(layer "F.Fab")
			(hide yes)
			(effects
				(font
					(size 1.27 1.27)
					(thickness 0.15)
				)
			)
		)
		(property "Author" "Antmicro"
			(at 207.63 365.87 0)
			(layer "B.Fab")
			(hide yes)
			(effects
				(font
					(size 1 1)
					(thickness 0.15)
				)
				(justify mirror)
			)
		)
		(property "Dielectric" ""
			(at 207.63 365.87 0)
			(layer "B.Fab")
			(hide yes)
			(effects
				(font
					(size 1 1)
					(thickness 0.15)
				)
				(justify mirror)
			)
		)
		(property "License" "Apache-2.0"
			(at 207.63 365.87 0)
			(layer "B.Fab")
			(hide yes)
			(effects
				(font
					(size 1 1)
					(thickness 0.15)
				)
				(justify mirror)
			)
		)
		(property "MPN" "CL10A226MO7JZNC"
			(at 207.63 365.87 0)
			(layer "B.Fab")
			(hide yes)
			(effects
				(font
					(size 1 1)
					(thickness 0.15)
				)
				(justify mirror)
			)
		)
		(property "Manufacturer" "Samsung Electro-Mechanics"
			(at 207.63 365.87 0)
			(layer "B.Fab")
			(hide yes)
			(effects
				(font
					(size 1 1)
					(thickness 0.15)
				)
				(justify mirror)
			)
		)
		(property "Public" "False"
			(at 207.63 365.87 0)
			(layer "B.Fab")
			(hide yes)
			(effects
				(font
					(size 1 1)
					(thickness 0.15)
				)
				(justify mirror)
			)
		)
		(property "Val" "22u"
			(at 207.63 365.87 0)
			(layer "B.Fab")
			(hide yes)
			(effects
				(font
					(size 1 1)
					(thickness 0.15)
				)
				(justify mirror)
			)
		)
		(property "Voltage" "16V"
			(at 207.63 365.87 0)
			(layer "B.Fab")
			(hide yes)
			(effects
				(font
					(size 1 1)
					(thickness 0.15)
				)
				(justify mirror)
			)
		)
		(sheetname "M.2 key M #2")
		(sheetfile "m2keym.kicad_sch")
		(attr smd)
		(fp_line
			(start 0.15 0.4)
			(end -0.15 0.4)
			(stroke
				(width 0.15)
				(type solid)
			)
			(layer "B.SilkS")
		)
		(fp_line
			(start 0.15 -0.4)
			(end -0.15 -0.4)
			(stroke
				(width 0.15)
				(type solid)
			)
			(layer "B.SilkS")
		)
		(fp_rect
			(start -1.25 0.65)
			(end 1.25 -0.65)
			(stroke
				(width 0.05)
				(type solid)
			)
			(fill no)
			(layer "B.CrtYd")
		)
		(fp_rect
			(start -0.8 0.4)
			(end 0.8 -0.4)
			(stroke
				(width 0.15)
				(type solid)
			)
			(fill no)
			(layer "B.Fab")
		)
		(pad "1" smd roundrect
			(at -0.7 0 270)
			(size 0.8 1)
			(layers "B.Cu" "B.Mask" "B.Paste")
			(roundrect_rratio 0.2)
			(net 1 "GND")
			(pintype "passive")
			(teardrops
				(best_length_ratio 0.2)
				(max_length 1)
				(best_width_ratio 0.9)
				(max_width 2)
				(curved_edges yes)
				(filter_ratio 0.9)
				(enabled yes)
				(allow_two_segments yes)
				(prefer_zone_connections yes)
			)
		)
		(pad "2" smd roundrect
			(at 0.7 0 270)
			(size 0.8 1)
			(layers "B.Cu" "B.Mask" "B.Paste")
			(roundrect_rratio 0.2)
			(net 970 "/M.2 key M #2/M2_3V3")
			(pintype "passive")
			(teardrops
				(best_length_ratio 0.2)
				(max_length 1)
				(best_width_ratio 0.9)
				(max_width 2)
				(curved_edges yes)
				(filter_ratio 0.9)
				(enabled yes)
				(allow_two_segments yes)
				(prefer_zone_connections yes)
			)
		)
	)
)
